(kicad_pcb
	(version 20260206)
	(generator "pcbnew")
	(generator_version "10.0")
	(general
		(thickness 1.6)
		(legacy_teardrops no)
	)
	(paper "A4")
	(title_block
		(title "04192023_DAF0TMB3IC0_F0TG_MB_C_brd_V02_OCP.brd")
		(comment 1 "Grand Teton / footprints 6539-6545 of 8354")
	)
	(layers
		(0 "F.Cu" signal "TOP")
		(4 "In1.Cu" signal "GND")
		(6 "In2.Cu" signal "IN1")
		(8 "In3.Cu" signal "GND1")
		(10 "In4.Cu" signal "IN2")
		(12 "In5.Cu" signal "GND2")
		(14 "In6.Cu" signal "IN3")
		(16 "In7.Cu" signal "GND3")
		(18 "In8.Cu" signal "VCC")
		(20 "In9.Cu" signal "VCC1")
		(22 "In10.Cu" signal "GND4")
		(24 "In11.Cu" signal "IN4")
		(26 "In12.Cu" signal "GND5")
		(28 "In13.Cu" signal "IN5")
		(30 "In14.Cu" signal "GND6")
		(32 "In15.Cu" signal "IN6")
		(34 "In16.Cu" signal "GND7")
		(2 "B.Cu" signal "BOTTOM")
		(9 "F.Adhes" user "F.Adhesive")
		(11 "B.Adhes" user "B.Adhesive")
		(13 "F.Paste" user "Package Geometry/Pastemask Top")
		(15 "B.Paste" user "Package Geometry/Pastemask Bottom")
		(5 "F.SilkS" user "Ref Des/Silkscreen Top")
		(7 "B.SilkS" user "Ref Des/Silkscreen Bottom")
		(1 "F.Mask" user "Board Geometry/Soldermask Top")
		(3 "B.Mask" user "Board Geometry/Soldermask Bottom")
		(17 "Dwgs.User" user "User.Drawings")
		(19 "Cmts.User" user "User.Comments")
		(21 "Eco1.User" user "User.Eco1")
		(23 "Eco2.User" user "User.Eco2")
		(25 "Edge.Cuts" user "Board Geometry/Outline")
		(27 "Margin" user)
		(31 "F.CrtYd" user "Package Geometry/Place Bound Top")
		(29 "B.CrtYd" user "Package Geometry/Place Bound Bottom")
		(35 "F.Fab" user "Ref Des/Assembly Top")
		(33 "B.Fab" user "Ref Des/Assembly Bottom")
	)
	(footprint ""
		(layer "B.Cu")
		(at 48.65624 -432.954938)
		(property "Reference" "Q101"
			(at -1.126998 -1.815846 0)
			(unlocked yes)
			(layer "B.SilkS")
			(effects
				(font
					(size 0.7874 0.5842)
					(thickness 0.1524)
				)
				(justify left mirror)
			)
		)
		(property "Value" ""
			(at 0 0 0)
			(layer "B.Fab")
			(effects
				(font
					(size 1.27 1.27)
				)
				(justify mirror)
			)
		)
		(duplicate_pad_numbers_are_jumpers no)
		(fp_line
			(start -1.332738 -1.100074)
			(end -1.332738 1.100074)
			(stroke
				(width 0.1524)
				(type default)
			)
			(layer "B.SilkS")
		)
		(fp_line
			(start -1.332738 1.100074)
			(end 1.332738 1.100074)
			(stroke
				(width 0.1524)
				(type default)
			)
			(layer "B.SilkS")
		)
		(fp_line
			(start -0.4826 -1.100074)
			(end -1.332738 -1.100074)
			(stroke
				(width 0.1524)
				(type default)
			)
			(layer "B.SilkS")
		)
		(fp_line
			(start 0 -0.541274)
			(end -0.4826 -1.100074)
			(stroke
				(width 0.1524)
				(type default)
			)
			(layer "B.SilkS")
		)
		(fp_line
			(start 0.4826 -1.100074)
			(end 0 -0.541274)
			(stroke
				(width 0.1524)
				(type default)
			)
			(layer "B.SilkS")
		)
		(fp_line
			(start 1.332738 -1.100074)
			(end 0.4826 -1.100074)
			(stroke
				(width 0.1524)
				(type default)
			)
			(layer "B.SilkS")
		)
		(fp_line
			(start 1.332738 1.100074)
			(end 1.332738 -1.100074)
			(stroke
				(width 0.1524)
				(type default)
			)
			(layer "B.SilkS")
		)
		(fp_poly
			(pts
				(xy 1.533144 -0.649986) (xy 2.2352 -0.298958) (xy 2.2352 -1.001014)
			)
			(stroke
				(width 0)
				(type default)
			)
			(fill yes)
			(layer "B.SilkS")
		)
		(fp_line
			(start -0.674878 -1.100074)
			(end -0.674878 1.100074)
			(stroke
				(width 0.1)
				(type default)
			)
			(layer "B.Fab")
		)
		(fp_line
			(start -0.674878 1.100074)
			(end 0.674878 1.100074)
			(stroke
				(width 0.1)
				(type default)
			)
			(layer "B.Fab")
		)
		(fp_line
			(start 0.674878 -1.100074)
			(end -0.674878 -1.100074)
			(stroke
				(width 0.1)
				(type default)
			)
			(layer "B.Fab")
		)
		(fp_line
			(start 0.674878 1.100074)
			(end 0.674878 -1.100074)
			(stroke
				(width 0.1)
				(type default)
			)
			(layer "B.Fab")
		)
		(fp_poly
			(pts
				(xy 2.2352 -0.298958) (xy 2.2352 -1.001014) (xy 1.533144 -0.649986)
			)
			(stroke
				(width 0)
				(type default)
			)
			(fill yes)
			(layer "B.Fab")
		)
		(pad "1" smd rect
			(at 0.94996 -0.649986 90)
			(size 0.4318 0.508)
			(layers "B.Cu" "B.Mask" "B.Paste")
			(net "GND")
		)
		(pad "2" smd rect
			(at 0.94996 0 90)
			(size 0.4318 0.508)
			(layers "B.Cu" "B.Mask" "B.Paste")
			(net "GPU_FPGA_THERM_OVERT_N")
		)
		(pad "3" smd rect
			(at 0.94996 0.649986 90)
			(size 0.4318 0.508)
			(layers "B.Cu" "B.Mask" "B.Paste")
			(net "GPU_FPGA_THERM_OVERT_ISO_N")
		)
		(pad "4" smd rect
			(at -0.94996 0.649986 90)
			(size 0.4318 0.508)
			(layers "B.Cu" "B.Mask" "B.Paste")
			(net "GND")
		)
		(pad "5" smd rect
			(at -0.94996 0 90)
			(size 0.4318 0.508)
			(layers "B.Cu" "B.Mask" "B.Paste")
			(net "GPU_FPGA_THERM_OVERT")
		)
		(pad "6" smd rect
			(at -0.94996 -0.649986 90)
			(size 0.4318 0.508)
			(layers "B.Cu" "B.Mask" "B.Paste")
			(net "GPU_FPGA_THERM_OVERT")
		)
	)
	(footprint ""
		(layer "B.Cu")
		(at 417.595558 -389.49503)
		(property "Reference" "C7014"
			(at 2.26314 2.989072 0)
			(unlocked yes)
			(layer "B.SilkS")
			(effects
				(font
					(size 0.7874 0.5842)
					(thickness 0.1524)
				)
				(justify left mirror)
			)
		)
		(property "Value" ""
			(at 0 0 0)
			(layer "B.Fab")
			(effects
				(font
					(size 1.27 1.27)
				)
				(justify mirror)
			)
		)
		(duplicate_pad_numbers_are_jumpers no)
		(fp_line
			(start -4.53898 -2.15011)
			(end -4.53898 2.15011)
			(stroke
				(width 0.1524)
				(type default)
			)
			(layer "B.SilkS")
		)
		(fp_line
			(start -4.53898 2.15011)
			(end 4.53898 2.15011)
			(stroke
				(width 0.1524)
				(type default)
			)
			(layer "B.SilkS")
		)
		(fp_line
			(start 4.53898 -2.150618)
			(end 4.539742 2.152142)
			(stroke
				(width 0.1524)
				(type default)
			)
			(layer "B.SilkS")
		)
		(fp_line
			(start 4.53898 -2.15011)
			(end -4.53898 -2.15011)
			(stroke
				(width 0.1524)
				(type default)
			)
			(layer "B.SilkS")
		)
		(fp_line
			(start 4.53898 2.15011)
			(end 4.53898 -2.15011)
			(stroke
				(width 0.1524)
				(type default)
			)
			(layer "B.SilkS")
		)
		(fp_line
			(start 4.69138 -2.150618)
			(end 4.692396 2.161032)
			(stroke
				(width 0.1524)
				(type default)
			)
			(layer "B.SilkS")
		)
		(fp_line
			(start 4.83108 2.150364)
			(end 4.447794 2.149348)
			(stroke
				(width 0.1524)
				(type default)
			)
			(layer "B.SilkS")
		)
		(fp_line
			(start 4.84378 -2.150618)
			(end 4.53898 -2.150618)
			(stroke
				(width 0.1524)
				(type default)
			)
			(layer "B.SilkS")
		)
		(fp_line
			(start 4.84378 -2.150618)
			(end 4.842256 2.163064)
			(stroke
				(width 0.1524)
				(type default)
			)
			(layer "B.SilkS")
		)
		(fp_line
			(start -3.64998 -2.15011)
			(end -3.64998 2.15011)
			(stroke
				(width 0.1)
				(type default)
			)
			(layer "B.Fab")
		)
		(fp_line
			(start -3.64998 2.15011)
			(end 3.64998 2.15011)
			(stroke
				(width 0.1)
				(type default)
			)
			(layer "B.Fab")
		)
		(fp_line
			(start 3.64998 -2.15011)
			(end -3.64998 -2.15011)
			(stroke
				(width 0.1)
				(type default)
			)
			(layer "B.Fab")
		)
		(fp_line
			(start 3.64998 2.15011)
			(end 3.64998 -2.15011)
			(stroke
				(width 0.1)
				(type default)
			)
			(layer "B.Fab")
		)
		(fp_text user "-"
			(at -2.944114 2.239772 0)
			(unlocked yes)
			(layer "B.SilkS")
			(effects
				(font
					(size 1.905 1.4224)
					(thickness 0.1524)
				)
				(justify left mirror)
			)
		)
		(fp_text user "+"
			(at 6.214872 -0.337058 0)
			(unlocked yes)
			(layer "B.SilkS")
			(effects
				(font
					(size 1.905 1.4224)
					(thickness 0.1524)
				)
				(justify left mirror)
			)
		)
		(fp_text user "-"
			(at -4.313174 -0.094488 0)
			(unlocked yes)
			(layer "B.Fab")
			(effects
				(font
					(size 1.905 1.4224)
					(thickness 0.1524)
				)
				(justify left mirror)
			)
		)
		(fp_text user "+"
			(at 6.214872 -0.337058 0)
			(unlocked yes)
			(layer "B.Fab")
			(effects
				(font
					(size 1.905 1.4224)
					(thickness 0.1524)
				)
				(justify left mirror)
			)
		)
		(pad "1" smd rect
			(at 3.199892 0 180)
			(size 2.413 2.8194)
			(layers "B.Cu" "B.Mask" "B.Paste")
			(net "P0V9_CPU0_RT2_2A")
		)
		(pad "2" smd rect
			(at -3.199892 0 180)
			(size 2.413 2.8194)
			(layers "B.Cu" "B.Mask" "B.Paste")
			(net "GND")
		)
	)
	(footprint ""
		(layer "B.Cu")
		(at 123.126754 -171.910248 90)
		(property "Reference" "PC337"
			(at 5.774436 1.227074 270)
			(unlocked yes)
			(layer "B.SilkS")
			(effects
				(font
					(size 0.7874 0.5842)
					(thickness 0.1524)
				)
				(justify left mirror)
			)
		)
		(property "Value" ""
			(at 0 0 90)
			(layer "B.Fab")
			(effects
				(font
					(size 1.27 1.27)
				)
				(justify mirror)
			)
		)
		(duplicate_pad_numbers_are_jumpers no)
		(fp_line
			(start 4.533392 -2.249932)
			(end -4.533392 -2.249932)
			(stroke
				(width 0.1524)
				(type default)
			)
			(layer "B.SilkS")
		)
		(fp_line
			(start -4.533392 -2.249932)
			(end -4.533392 2.249932)
			(stroke
				(width 0.1524)
				(type default)
			)
			(layer "B.SilkS")
		)
		(fp_line
			(start 4.533392 2.249932)
			(end 4.533392 -2.249932)
			(stroke
				(width 0.1524)
				(type default)
			)
			(layer "B.SilkS")
		)
		(fp_line
			(start -4.533392 2.249932)
			(end 4.533392 2.249932)
			(stroke
				(width 0.1524)
				(type default)
			)
			(layer "B.SilkS")
		)
		(fp_rect
			(start 4.533392 -2.326132)
			(end 5.39242 2.326132)
			(stroke
				(width 0)
				(type default)
			)
			(fill yes)
			(layer "B.SilkS")
		)
		(fp_line
			(start 3.750056 -2.249932)
			(end -3.750056 -2.249932)
			(stroke
				(width 0.1)
				(type default)
			)
			(layer "B.Fab")
		)
		(fp_line
			(start -3.750056 -2.249932)
			(end -3.750056 2.249932)
			(stroke
				(width 0.1)
				(type default)
			)
			(layer "B.Fab")
		)
		(fp_line
			(start 3.750056 2.249932)
			(end 3.750056 -2.249932)
			(stroke
				(width 0.1)
				(type default)
			)
			(layer "B.Fab")
		)
		(fp_line
			(start -3.750056 2.249932)
			(end 3.750056 2.249932)
			(stroke
				(width 0.1)
				(type default)
			)
			(layer "B.Fab")
		)
		(fp_text user "+"
			(at 6.322314 0.786384 0)
			(unlocked yes)
			(layer "B.SilkS")
			(effects
				(font
					(size 1.905 1.4224)
					(thickness 0.1524)
				)
				(justify left mirror)
			)
		)
		(fp_text user "-"
			(at -4.732274 1.216152 90)
			(unlocked yes)
			(layer "B.SilkS")
			(effects
				(font
					(size 1.905 1.4224)
					(thickness 0.1524)
				)
				(justify left mirror)
			)
		)
		(fp_text user "-"
			(at -4.8514 -0.14605 90)
			(unlocked yes)
			(layer "B.Fab")
			(effects
				(font
					(size 1.905 1.4224)
					(thickness 0.1524)
				)
				(justify left mirror)
			)
		)
		(fp_text user "+"
			(at 6.322314 0.786384 0)
			(unlocked yes)
			(layer "B.Fab")
			(effects
				(font
					(size 1.905 1.4224)
					(thickness 0.1524)
				)
				(justify left mirror)
			)
		)
		(pad "1" smd rect
			(at 3.199892 0 270)
			(size 2.413 2.8194)
			(layers "B.Cu" "B.Mask" "B.Paste")
			(net "PVDDCR_SOC_P1")
		)
		(pad "2" smd rect
			(at -3.199892 0 270)
			(size 2.413 2.8194)
			(layers "B.Cu" "B.Mask" "B.Paste")
			(net "GND")
		)
	)
	(footprint ""
		(layer "B.Cu")
		(at 425.896532 -358.570276)
		(property "Reference" "PC8005"
			(at 0 0 0)
			(layer "B.SilkS")
			(hide yes)
			(effects
				(font
					(size 1.27 1.27)
				)
				(justify mirror)
			)
		)
		(property "Value" ""
			(at 0 0 0)
			(layer "B.Fab")
			(effects
				(font
					(size 1.27 1.27)
				)
				(justify mirror)
			)
		)
		(duplicate_pad_numbers_are_jumpers no)
		(fp_line
			(start -1.524 -0.762)
			(end -1.524 0.762)
			(stroke
				(width 0.1524)
				(type default)
			)
			(layer "B.SilkS")
		)
		(fp_line
			(start -1.524 0.762)
			(end 1.524 0.762)
			(stroke
				(width 0.1524)
				(type default)
			)
			(layer "B.SilkS")
		)
		(fp_line
			(start 1.524 -0.762)
			(end -1.524 -0.762)
			(stroke
				(width 0.1524)
				(type default)
			)
			(layer "B.SilkS")
		)
		(fp_line
			(start 1.524 0.762)
			(end 1.524 -0.762)
			(stroke
				(width 0.1524)
				(type default)
			)
			(layer "B.SilkS")
		)
		(fp_line
			(start -1.1049 -0.724916)
			(end 1.1049 -0.724916)
			(stroke
				(width 0.1)
				(type default)
			)
			(layer "B.Fab")
		)
		(fp_line
			(start -1.1049 0.724916)
			(end -1.1049 -0.724916)
			(stroke
				(width 0.1)
				(type default)
			)
			(layer "B.Fab")
		)
		(fp_line
			(start 1.1049 -0.724916)
			(end 1.1049 0.724916)
			(stroke
				(width 0.1)
				(type default)
			)
			(layer "B.Fab")
		)
		(fp_line
			(start 1.1049 0.724916)
			(end -1.1049 0.724916)
			(stroke
				(width 0.1)
				(type default)
			)
			(layer "B.Fab")
		)
		(pad "1" smd rect
			(at 0.889 0)
			(size 1.016 1.27)
			(layers "B.Cu" "B.Mask" "B.Paste")
			(net "SW_P12V_AUX_PVDD11_S3_P0_FLT")
		)
		(pad "2" smd rect
			(at -0.889 0)
			(size 1.016 1.27)
			(layers "B.Cu" "B.Mask" "B.Paste")
			(net "GND")
		)
	)
	(footprint ""
		(layer "B.Cu")
		(at 301.388272 -425.498768 180)
		(property "Reference" "R667"
			(at 0 0 0)
			(layer "B.SilkS")
			(hide yes)
			(effects
				(font
					(size 1.27 1.27)
				)
				(justify mirror)
			)
		)
		(property "Value" ""
			(at 0 0 0)
			(layer "B.Fab")
			(effects
				(font
					(size 1.27 1.27)
				)
				(justify mirror)
			)
		)
		(duplicate_pad_numbers_are_jumpers no)
		(fp_line
			(start 0.32512 0.175006)
			(end 0.32512 -0.175006)
			(stroke
				(width 0.1)
				(type default)
			)
			(layer "B.Fab")
		)
		(fp_line
			(start 0.32512 -0.175006)
			(end -0.32512 -0.175006)
			(stroke
				(width 0.1)
				(type default)
			)
			(layer "B.Fab")
		)
		(fp_line
			(start -0.32512 0.175006)
			(end 0.32512 0.175006)
			(stroke
				(width 0.1)
				(type default)
			)
			(layer "B.Fab")
		)
		(fp_line
			(start -0.32512 -0.175006)
			(end -0.32512 0.175006)
			(stroke
				(width 0.1)
				(type default)
			)
			(layer "B.Fab")
		)
		(pad "1" smd rect
			(at 0.2667 0)
			(size 0.3048 0.381)
			(layers "B.Cu" "B.Mask" "B.Paste")
			(net "SMB_RT_CPU0_P0_ROM_MUX_1D_SDA")
		)
		(pad "2" smd rect
			(at -0.2667 0 180)
			(size 0.3048 0.381)
			(layers "B.Cu" "B.Mask" "B.Paste")
			(net "SMB_RT_CPU0_P0_ROM_MUX_1D_R_SDA")
		)
	)
	(footprint ""
		(layer "B.Cu")
		(at 121.066306 -79.737458 90)
		(property "Reference" "R6245"
			(at 0 0 90)
			(layer "B.SilkS")
			(hide yes)
			(effects
				(font
					(size 1.27 1.27)
				)
				(justify mirror)
			)
		)
		(property "Value" ""
			(at 0 0 90)
			(layer "B.Fab")
			(effects
				(font
					(size 1.27 1.27)
				)
				(justify mirror)
			)
		)
		(duplicate_pad_numbers_are_jumpers no)
		(fp_line
			(start 0.7874 -0.4064)
			(end -0.7874 -0.4064)
			(stroke
				(width 0.1524)
				(type default)
			)
			(layer "B.SilkS")
		)
		(fp_line
			(start -0.7874 -0.4064)
			(end -0.7874 0.4064)
			(stroke
				(width 0.1524)
				(type default)
			)
			(layer "B.SilkS")
		)
		(fp_line
			(start 0.7874 0.4064)
			(end 0.7874 -0.4064)
			(stroke
				(width 0.1524)
				(type default)
			)
			(layer "B.SilkS")
		)
		(fp_line
			(start -0.7874 0.4064)
			(end 0.7874 0.4064)
			(stroke
				(width 0.1524)
				(type default)
			)
			(layer "B.SilkS")
		)
		(fp_line
			(start 0.67945 -0.305054)
			(end 0.12065 -0.305054)
			(stroke
				(width 0.1)
				(type default)
			)
			(layer "B.Fab")
		)
		(fp_line
			(start 0.12065 -0.305054)
			(end 0.12065 -0.2794)
			(stroke
				(width 0.1)
				(type default)
			)
			(layer "B.Fab")
		)
		(fp_line
			(start -0.12065 -0.3048)
			(end -0.67945 -0.3048)
			(stroke
				(width 0.1)
				(type default)
			)
			(layer "B.Fab")
		)
		(fp_line
			(start -0.67945 -0.3048)
			(end -0.67945 0.3048)
			(stroke
				(width 0.1)
				(type default)
			)
			(layer "B.Fab")
		)
		(fp_line
			(start 0.12065 -0.2794)
			(end -0.12065 -0.2794)
			(stroke
				(width 0.1)
				(type default)
			)
			(layer "B.Fab")
		)
		(fp_line
			(start -0.12065 -0.2794)
			(end -0.12065 -0.3048)
			(stroke
				(width 0.1)
				(type default)
			)
			(layer "B.Fab")
		)
		(fp_line
			(start 0.12065 0.2794)
			(end 0.12065 0.3048)
			(stroke
				(width 0.1)
				(type default)
			)
			(layer "B.Fab")
		)
		(fp_line
			(start -0.120396 0.2794)
			(end 0.12065 0.2794)
			(stroke
				(width 0.1)
				(type default)
			)
			(layer "B.Fab")
		)
		(fp_line
			(start 0.67945 0.3048)
			(end 0.67945 -0.305054)
			(stroke
				(width 0.1)
				(type default)
			)
			(layer "B.Fab")
		)
		(fp_line
			(start 0.12065 0.3048)
			(end 0.67945 0.3048)
			(stroke
				(width 0.1)
				(type default)
			)
			(layer "B.Fab")
		)
		(fp_line
			(start -0.120396 0.3048)
			(end -0.120396 0.2794)
			(stroke
				(width 0.1)
				(type default)
			)
			(layer "B.Fab")
		)
		(fp_line
			(start -0.67945 0.3048)
			(end -0.120396 0.3048)
			(stroke
				(width 0.1)
				(type default)
			)
			(layer "B.Fab")
		)
		(pad "1" smd circle
			(at 0.40005 0 270)
			(size 0 0)
			(layers "B.Cu" "B.Mask" "B.Paste")
			(net "P3V3_AUX")
		)
		(pad "2" smd circle
			(at -0.40005 0 270)
			(size 0 0)
			(layers "B.Cu" "B.Mask" "B.Paste")
			(net "P1V2_AUX_VCC")
		)
	)
	(footprint ""
		(layer "B.Cu")
		(at 237.88116 -328.724514)
		(property "Reference" "R1236"
			(at 0 0 0)
			(layer "B.SilkS")
			(hide yes)
			(effects
				(font
					(size 1.27 1.27)
				)
				(justify mirror)
			)
		)
		(property "Value" ""
			(at 0 0 0)
			(layer "B.Fab")
			(effects
				(font
					(size 1.27 1.27)
				)
				(justify mirror)
			)
		)
		(duplicate_pad_numbers_are_jumpers no)
		(fp_line
			(start -0.7874 -0.4064)
			(end -0.7874 0.4064)
			(stroke
				(width 0.1524)
				(type default)
			)
			(layer "B.SilkS")
		)
		(fp_line
			(start -0.7874 0.4064)
			(end 0.7874 0.4064)
			(stroke
				(width 0.1524)
				(type default)
			)
			(layer "B.SilkS")
		)
		(fp_line
			(start 0.7874 -0.4064)
			(end -0.7874 -0.4064)
			(stroke
				(width 0.1524)
				(type default)
			)
			(layer "B.SilkS")
		)
		(fp_line
			(start 0.7874 0.4064)
			(end 0.7874 -0.4064)
			(stroke
				(width 0.1524)
				(type default)
			)
			(layer "B.SilkS")
		)
		(fp_line
			(start -0.67945 -0.3048)
			(end -0.67945 0.3048)
			(stroke
				(width 0.1)
				(type default)
			)
			(layer "B.Fab")
		)
		(fp_line
			(start -0.67945 0.3048)
			(end -0.120396 0.3048)
			(stroke
				(width 0.1)
				(type default)
			)
			(layer "B.Fab")
		)
		(fp_line
			(start -0.12065 -0.3048)
			(end -0.67945 -0.3048)
			(stroke
				(width 0.1)
				(type default)
			)
			(layer "B.Fab")
		)
		(fp_line
			(start -0.12065 -0.2794)
			(end -0.12065 -0.3048)
			(stroke
				(width 0.1)
				(type default)
			)
			(layer "B.Fab")
		)
		(fp_line
			(start -0.120396 0.2794)
			(end 0.12065 0.2794)
			(stroke
				(width 0.1)
				(type default)
			)
			(layer "B.Fab")
		)
		(fp_line
			(start -0.120396 0.3048)
			(end -0.120396 0.2794)
			(stroke
				(width 0.1)
				(type default)
			)
			(layer "B.Fab")
		)
		(fp_line
			(start 0.12065 -0.305054)
			(end 0.12065 -0.2794)
			(stroke
				(width 0.1)
				(type default)
			)
			(layer "B.Fab")
		)
		(fp_line
			(start 0.12065 -0.2794)
			(end -0.12065 -0.2794)
			(stroke
				(width 0.1)
				(type default)
			)
			(layer "B.Fab")
		)
		(fp_line
			(start 0.12065 0.2794)
			(end 0.12065 0.3048)
			(stroke
				(width 0.1)
				(type default)
			)
			(layer "B.Fab")
		)
		(fp_line
			(start 0.12065 0.3048)
			(end 0.67945 0.3048)
			(stroke
				(width 0.1)
				(type default)
			)
			(layer "B.Fab")
		)
		(fp_line
			(start 0.67945 -0.305054)
			(end 0.12065 -0.305054)
			(stroke
				(width 0.1)
				(type default)
			)
			(layer "B.Fab")
		)
		(fp_line
			(start 0.67945 0.3048)
			(end 0.67945 -0.305054)
			(stroke
				(width 0.1)
				(type default)
			)
			(layer "B.Fab")
		)
		(pad "1" smd circle
			(at 0.40005 0 180)
			(size 0 0)
			(layers "B.Cu" "B.Mask" "B.Paste")
			(net "PVDD18_S5_P1")
		)
		(pad "2" smd circle
			(at -0.40005 0 180)
			(size 0 0)
			(layers "B.Cu" "B.Mask" "B.Paste")
			(net "PVDD18_S5_P1_ADC")
		)
	)
)
